(kicad_pcb
	(version 20241229)
	(generator "pcbnew")
	(generator_version "9.0")
	(general
		(thickness 1.62)
		(legacy_teardrops no)
	)
	(paper "A4")
	(title_block
		(title "OCuLink to 10GbE adapter")
		(date "2026-02-23")
		(rev "1.1.0")
		(company "Antmicro Ltd")
		(comment 1 "www.antmicro.com")
		(comment 9 "footprints 152-157 of 510")
	)
	(layers
		(0 "F.Cu" signal)
		(4 "In1.Cu" signal)
		(6 "In2.Cu" signal)
		(8 "In3.Cu" signal)
		(10 "In4.Cu" signal)
		(12 "In5.Cu" signal)
		(14 "In6.Cu" signal)
		(2 "B.Cu" signal)
		(9 "F.Adhes" user "F.Adhesive")
		(11 "B.Adhes" user "B.Adhesive")
		(13 "F.Paste" user)
		(15 "B.Paste" user)
		(5 "F.SilkS" user "F.Silkscreen")
		(7 "B.SilkS" user "B.Silkscreen")
		(1 "F.Mask" user)
		(3 "B.Mask" user)
		(17 "Dwgs.User" user "User.Drawings")
		(19 "Cmts.User" user "User.Comments")
		(21 "Eco1.User" user "User.Eco1")
		(23 "Eco2.User" user "User.Eco2")
		(25 "Edge.Cuts" user)
		(27 "Margin" user)
		(31 "F.CrtYd" user "F.Courtyard")
		(29 "B.CrtYd" user "B.Courtyard")
		(35 "F.Fab" user)
		(33 "B.Fab" user)
	)
	(footprint "antmicro-footprints:MP_Pad6mm_Drill3.2mm"
		(layer "F.Cu")
		(at 113 54.250001)
		(property "Reference" "MP3"
			(at 1.25 -2.950001 0)
			(layer "F.SilkS")
			(hide yes)
			(effects
				(font
					(size 0.7 0.7)
					(thickness 0.15)
				)
				(justify left bottom)
			)
		)
		(property "Value" "MP_Pad6mm_Drill3.2mm"
			(at 0 3.9 0)
			(layer "F.Fab")
			(hide yes)
			(effects
				(font
					(size 0.7 0.7)
					(thickness 0.15)
				)
				(justify left bottom)
			)
		)
		(property "Description" "Mechanical part"
			(at 0 0 0)
			(layer "F.Fab")
			(hide yes)
			(effects
				(font
					(size 1.27 1.27)
					(thickness 0.15)
				)
			)
		)
		(property "Author" "Antmicro"
			(at 0 0 0)
			(unlocked yes)
			(layer "F.Fab")
			(hide yes)
			(effects
				(font
					(size 1 1)
					(thickness 0.15)
				)
			)
		)
		(property "License" "Apache-2.0"
			(at 0 0 0)
			(unlocked yes)
			(layer "F.Fab")
			(hide yes)
			(effects
				(font
					(size 1 1)
					(thickness 0.15)
				)
			)
		)
		(sheetname "/")
		(sheetfile "oculink-to-10gbe-adapter.kicad_sch")
		(attr exclude_from_pos_files exclude_from_bom)
		(fp_circle
			(center 0 0)
			(end 3.25 0)
			(stroke
				(width 0.05)
				(type default)
			)
			(fill no)
			(layer "F.CrtYd")
		)
		(pad "1" thru_hole circle
			(at 0 0)
			(size 6 6)
			(drill 3.2)
			(layers "*.Cu" "*.Mask")
			(remove_unused_layers no)
			(net 28 "GND")
			(pintype "passive")
		)
	)
	(footprint "antmicro-footprints:C_0402_1005Metric"
		(layer "F.Cu")
		(at 73.849999 79.039995)
		(descr "Capacitor SMD 0402")
		(tags "capacitor SMD 0402")
		(property "Reference" "C2"
			(at -3.749999 -8.439995 0)
			(layer "F.SilkS")
			(effects
				(font
					(size 0.7 0.7)
					(thickness 0.15)
				)
				(justify left bottom)
			)
		)
		(property "Value" "C_33p_0402"
			(at -1.022927 2.155213 0)
			(layer "F.Fab")
			(hide yes)
			(effects
				(font
					(size 0.7 0.7)
					(thickness 0.15)
				)
				(justify left bottom)
			)
		)
		(property "Datasheet" "https://spicat.kyocera-avx.com/product/mlcc/chartview/04025A330FAT2A/"
			(at 0 0 0)
			(layer "F.Fab")
			(hide yes)
			(effects
				(font
					(size 1.27 1.27)
					(thickness 0.15)
				)
			)
		)
		(property "Description" "SMD Multilayer Ceramic Capacitor, 33 pF, 50 V, 0402 [1005 Metric], ± 5%, C0G / NP0, MC"
			(at 0 0 0)
			(layer "F.Fab")
			(hide yes)
			(effects
				(font
					(size 1.27 1.27)
					(thickness 0.15)
				)
			)
		)
		(property "MPN" "04025A330FAT2A"
			(at 0 0 0)
			(unlocked yes)
			(layer "F.Fab")
			(hide yes)
			(effects
				(font
					(size 1 1)
					(thickness 0.15)
				)
			)
		)
		(property "Manufacturer" "KYOCERA AVX"
			(at 0 0 0)
			(unlocked yes)
			(layer "F.Fab")
			(hide yes)
			(effects
				(font
					(size 1 1)
					(thickness 0.15)
				)
			)
		)
		(property "License" "Apache-2.0"
			(at 0 0 0)
			(unlocked yes)
			(layer "F.Fab")
			(hide yes)
			(effects
				(font
					(size 1 1)
					(thickness 0.15)
				)
			)
		)
		(property "Author" "Antmicro"
			(at 0 0 0)
			(unlocked yes)
			(layer "F.Fab")
			(hide yes)
			(effects
				(font
					(size 1 1)
					(thickness 0.15)
				)
			)
		)
		(property "Val" "33p"
			(at 0 0 0)
			(unlocked yes)
			(layer "F.Fab")
			(hide yes)
			(effects
				(font
					(size 1 1)
					(thickness 0.15)
				)
			)
		)
		(property "Voltage" ""
			(at 0 0 0)
			(unlocked yes)
			(layer "F.Fab")
			(hide yes)
			(effects
				(font
					(size 1 1)
					(thickness 0.15)
				)
			)
		)
		(property "Dielectric" ""
			(at 0 0 0)
			(unlocked yes)
			(layer "F.Fab")
			(hide yes)
			(effects
				(font
					(size 1 1)
					(thickness 0.15)
				)
			)
		)
		(sheetname "/Power/")
		(sheetfile "power.kicad_sch")
		(attr smd)
		(fp_rect
			(start -0.925 -0.47)
			(end 0.925 0.47)
			(stroke
				(width 0.05)
				(type default)
			)
			(fill no)
			(layer "F.CrtYd")
		)
		(fp_line
			(start -0.494 -0.25)
			(end 0.504 -0.25)
			(stroke
				(width 0.15)
				(type solid)
			)
			(layer "F.Fab")
		)
		(fp_line
			(start -0.494 0.248)
			(end -0.494 -0.25)
			(stroke
				(width 0.15)
				(type solid)
			)
			(layer "F.Fab")
		)
		(fp_line
			(start 0.504 -0.25)
			(end 0.504 0.248)
			(stroke
				(width 0.15)
				(type solid)
			)
			(layer "F.Fab")
		)
		(fp_line
			(start 0.504 0.248)
			(end -0.494 0.248)
			(stroke
				(width 0.15)
				(type solid)
			)
			(layer "F.Fab")
		)
		(pad "1" smd roundrect
			(at -0.48 0)
			(size 0.59 0.64)
			(layers "F.Cu" "F.Mask" "F.Paste")
			(roundrect_rratio 0.25)
			(net 317 "/Power/3V3_FB")
			(pintype "passive")
		)
		(pad "2" smd roundrect
			(at 0.48 0)
			(size 0.59 0.64)
			(layers "F.Cu" "F.Mask" "F.Paste")
			(roundrect_rratio 0.25)
			(net 255 "/Power/+3V3_OUT")
			(pintype "passive")
		)
	)
	(footprint "antmicro-footprints:R_0402_1005Metric"
		(layer "F.Cu")
		(at 56.100001 108.249997 90)
		(descr "Resistor SMD 0402")
		(tags "resistor SMD 0402")
		(property "Reference" "R21"
			(at -7.800003 2.709999 270)
			(layer "F.SilkS")
			(effects
				(font
					(size 0.7 0.7)
					(thickness 0.15)
				)
				(justify left bottom)
			)
		)
		(property "Value" "R_20k_0402"
			(at -1.011843 1.772046 90)
			(layer "F.Fab")
			(hide yes)
			(effects
				(font
					(size 0.7 0.7)
					(thickness 0.15)
				)
				(justify left bottom)
			)
		)
		(property "Datasheet" "https://www.bourns.com/docs/product-datasheets/cr.pdf"
			(at 0 0 90)
			(layer "F.Fab")
			(hide yes)
			(effects
				(font
					(size 1.27 1.27)
					(thickness 0.15)
				)
			)
		)
		(property "Description" "SMD Chip Resistor, 20 kohm, ± 1%, 62.5 mW, 0402 [1005 Metric], Thick Film, General Purpose"
			(at 0 0 90)
			(layer "F.Fab")
			(hide yes)
			(effects
				(font
					(size 1.27 1.27)
					(thickness 0.15)
				)
			)
		)
		(property "MPN" "CR0402-FX-2002GLF"
			(at 0 0 90)
			(unlocked yes)
			(layer "F.Fab")
			(hide yes)
			(effects
				(font
					(size 1 1)
					(thickness 0.15)
				)
			)
		)
		(property "Manufacturer" "Bourns"
			(at 0 0 90)
			(unlocked yes)
			(layer "F.Fab")
			(hide yes)
			(effects
				(font
					(size 1 1)
					(thickness 0.15)
				)
			)
		)
		(property "License" "Apache-2.0"
			(at 0 0 90)
			(unlocked yes)
			(layer "F.Fab")
			(hide yes)
			(effects
				(font
					(size 1 1)
					(thickness 0.15)
				)
			)
		)
		(property "Author" "Antmicro"
			(at 0 0 90)
			(unlocked yes)
			(layer "F.Fab")
			(hide yes)
			(effects
				(font
					(size 1 1)
					(thickness 0.15)
				)
			)
		)
		(property "Val" "20k"
			(at 0 0 90)
			(unlocked yes)
			(layer "F.Fab")
			(hide yes)
			(effects
				(font
					(size 1 1)
					(thickness 0.15)
				)
			)
		)
		(property "Tolerance" "1%"
			(at 0 0 90)
			(unlocked yes)
			(layer "F.Fab")
			(hide yes)
			(effects
				(font
					(size 1 1)
					(thickness 0.15)
				)
			)
		)
		(sheetname "/Power/")
		(sheetfile "power.kicad_sch")
		(attr smd)
		(fp_rect
			(start -0.925 -0.47)
			(end 0.925 0.47)
			(stroke
				(width 0.05)
				(type default)
			)
			(fill no)
			(layer "F.CrtYd")
		)
		(fp_rect
			(start -0.5 -0.25)
			(end 0.5 0.25)
			(stroke
				(width 0.15)
				(type solid)
			)
			(fill no)
			(layer "F.Fab")
		)
		(pad "1" smd roundrect
			(at -0.48 0 90)
			(size 0.59 0.64)
			(layers "F.Cu" "F.Mask" "F.Paste")
			(roundrect_rratio 0.25)
			(net 332 "/Power/1V0_FB")
			(pintype "passive")
		)
		(pad "2" smd roundrect
			(at 0.48 0 90)
			(size 0.59 0.64)
			(layers "F.Cu" "F.Mask" "F.Paste")
			(roundrect_rratio 0.25)
			(net 312 "/Power/+1V0_OUT")
			(pintype "passive")
		)
	)
	(footprint "antmicro-footprints:R_0402_1005Metric"
		(layer "F.Cu")
		(at 101.3 103.3)
		(descr "Resistor SMD 0402")
		(tags "resistor SMD 0402")
		(property "Reference" "R87"
			(at -0.8 15.05 0)
			(layer "F.SilkS")
			(effects
				(font
					(size 0.7 0.7)
					(thickness 0.15)
				)
				(justify left bottom)
			)
		)
		(property "Value" "R_100k_0402"
			(at -1.011843 1.772046 0)
			(layer "F.Fab")
			(hide yes)
			(effects
				(font
					(size 0.7 0.7)
					(thickness 0.15)
				)
				(justify left bottom)
			)
		)
		(property "Datasheet" "https://www.bourns.com/docs/product-datasheets/cr.pdf"
			(at 0 0 0)
			(layer "F.Fab")
			(hide yes)
			(effects
				(font
					(size 1.27 1.27)
					(thickness 0.15)
				)
			)
		)
		(property "Description" "SMD Chip Resistor, 100 kohm, ± 1%, 62.5 mW, 0402 [1005 Metric], Thick Film, General Purpose"
			(at 0 0 0)
			(layer "F.Fab")
			(hide yes)
			(effects
				(font
					(size 1.27 1.27)
					(thickness 0.15)
				)
			)
		)
		(property "MPN" "CR0402-FX-1003GLF"
			(at 0 0 0)
			(unlocked yes)
			(layer "F.Fab")
			(hide yes)
			(effects
				(font
					(size 1 1)
					(thickness 0.15)
				)
			)
		)
		(property "Manufacturer" "Bourns"
			(at 0 0 0)
			(unlocked yes)
			(layer "F.Fab")
			(hide yes)
			(effects
				(font
					(size 1 1)
					(thickness 0.15)
				)
			)
		)
		(property "License" "Apache-2.0"
			(at 0 0 0)
			(unlocked yes)
			(layer "F.Fab")
			(hide yes)
			(effects
				(font
					(size 1 1)
					(thickness 0.15)
				)
			)
		)
		(property "Author" "Antmicro"
			(at 0 0 0)
			(unlocked yes)
			(layer "F.Fab")
			(hide yes)
			(effects
				(font
					(size 1 1)
					(thickness 0.15)
				)
			)
		)
		(property "Val" "100k"
			(at 0 0 0)
			(unlocked yes)
			(layer "F.Fab")
			(hide yes)
			(effects
				(font
					(size 1 1)
					(thickness 0.15)
				)
			)
		)
		(property "Tolerance" "1%"
			(at 0 0 0)
			(unlocked yes)
			(layer "F.Fab")
			(hide yes)
			(effects
				(font
					(size 1 1)
					(thickness 0.15)
				)
			)
		)
		(sheetname "/X710-AT2 Misc/")
		(sheetfile "x710-at2-mics.kicad_sch")
		(attr smd)
		(fp_rect
			(start -0.925 -0.47)
			(end 0.925 0.47)
			(stroke
				(width 0.05)
				(type default)
			)
			(fill no)
			(layer "F.CrtYd")
		)
		(fp_rect
			(start -0.5 -0.25)
			(end 0.5 0.25)
			(stroke
				(width 0.15)
				(type solid)
			)
			(fill no)
			(layer "F.Fab")
		)
		(pad "1" smd roundrect
			(at -0.48 0)
			(size 0.59 0.64)
			(layers "F.Cu" "F.Mask" "F.Paste")
			(roundrect_rratio 0.25)
			(net 28 "GND")
			(pintype "passive")
		)
		(pad "2" smd roundrect
			(at 0.48 0)
			(size 0.59 0.64)
			(layers "F.Cu" "F.Mask" "F.Paste")
			(roundrect_rratio 0.25)
			(net 366 "/X710-AT2 Misc/NCSI.TX_EN")
			(pintype "passive")
		)
	)
	(footprint "antmicro-footprints:R_0402_1005Metric"
		(layer "F.Cu")
		(at 80.349999 83.15 180)
		(descr "Resistor SMD 0402")
		(tags "resistor SMD 0402")
		(property "Reference" "R105"
			(at -1.050001 1.6 0)
			(layer "F.SilkS")
			(effects
				(font
					(size 0.7 0.7)
					(thickness 0.15)
				)
				(justify right bottom)
			)
		)
		(property "Value" "R_0R_0402"
			(at -1.011843 1.772046 0)
			(layer "F.Fab")
			(hide yes)
			(effects
				(font
					(size 0.7 0.7)
					(thickness 0.15)
				)
				(justify right top)
			)
		)
		(property "Datasheet" "https://industrial.panasonic.com/cdbs/www-data/pdf/RDA0000/AOA0000C301.pdf"
			(at 0 0 0)
			(layer "F.Fab")
			(hide yes)
			(effects
				(font
					(size 1.27 1.27)
					(thickness 0.15)
				)
			)
		)
		(property "Description" "SMD Chip Resistor, Jumper, 0 ohm, 100 mW, 0402 [1005 Metric], Thick Film, General Purpose"
			(at 0 0 0)
			(layer "F.Fab")
			(hide yes)
			(effects
				(font
					(size 1.27 1.27)
					(thickness 0.15)
				)
			)
		)
		(property "MPN" "ERJ2GE0R00X"
			(at 0 0 180)
			(unlocked yes)
			(layer "F.Fab")
			(hide yes)
			(effects
				(font
					(size 1 1)
					(thickness 0.15)
				)
			)
		)
		(property "Manufacturer" "Panasonic"
			(at 0 0 180)
			(unlocked yes)
			(layer "F.Fab")
			(hide yes)
			(effects
				(font
					(size 1 1)
					(thickness 0.15)
				)
			)
		)
		(property "License" "Apache-2.0"
			(at 0 0 180)
			(unlocked yes)
			(layer "F.Fab")
			(hide yes)
			(effects
				(font
					(size 1 1)
					(thickness 0.15)
				)
			)
		)
		(property "Author" "Antmicro"
			(at 0 0 180)
			(unlocked yes)
			(layer "F.Fab")
			(hide yes)
			(effects
				(font
					(size 1 1)
					(thickness 0.15)
				)
			)
		)
		(property "Val" "0R"
			(at 0 0 180)
			(unlocked yes)
			(layer "F.Fab")
			(hide yes)
			(effects
				(font
					(size 1 1)
					(thickness 0.15)
				)
			)
		)
		(property "Tolerance" "~"
			(at 0 0 180)
			(unlocked yes)
			(layer "F.Fab")
			(hide yes)
			(effects
				(font
					(size 1 1)
					(thickness 0.15)
				)
			)
		)
		(property "Current" "1A"
			(at 0 0 180)
			(unlocked yes)
			(layer "F.Fab")
			(hide yes)
			(effects
				(font
					(size 1 1)
					(thickness 0.15)
				)
			)
		)
		(sheetname "/X710-AT2 Misc/")
		(sheetfile "x710-at2-mics.kicad_sch")
		(attr smd)
		(fp_rect
			(start -0.925 -0.47)
			(end 0.925 0.47)
			(stroke
				(width 0.05)
				(type default)
			)
			(fill no)
			(layer "F.CrtYd")
		)
		(fp_rect
			(start -0.5 -0.25)
			(end 0.5 0.25)
			(stroke
				(width 0.15)
				(type solid)
			)
			(fill no)
			(layer "F.Fab")
		)
		(pad "1" smd roundrect
			(at -0.48 0 180)
			(size 0.59 0.64)
			(layers "F.Cu" "F.Mask" "F.Paste")
			(roundrect_rratio 0.25)
			(net 308 "/OCuLink/~{PE_RST}")
			(pintype "passive")
		)
		(pad "2" smd roundrect
			(at 0.48 0 180)
			(size 0.59 0.64)
			(layers "F.Cu" "F.Mask" "F.Paste")
			(roundrect_rratio 0.25)
			(net 396 "Net-(U10-A)")
			(pintype "passive")
		)
	)
	(footprint "antmicro-footprints:Oscillator_SMD_Skyworks_SI511_5x3.2x1.17mm"
		(layer "F.Cu")
		(at 104.7 109.235 180)
		(property "Reference" "Y1"
			(at 1.7 2.785 0)
			(layer "F.SilkS")
			(effects
				(font
					(size 0.7 0.7)
					(thickness 0.15)
				)
				(justify left bottom)
			)
		)
		(property "Value" "Oscillator_25MHz_511ABA25M0000BAGR"
			(at -2.75 3.85 0)
			(layer "F.Fab")
			(hide yes)
			(effects
				(font
					(size 0.7 0.7)
					(thickness 0.15)
				)
				(justify right top)
			)
		)
		(property "Datasheet" "https://www.mouser.com/datasheet/2/472/si510_11-2507765.pdf"
			(at 0 0 0)
			(layer "F.Fab")
			(hide yes)
			(effects
				(font
					(size 0.7 0.7)
					(thickness 0.15)
				)
				(justify right top)
			)
		)
		(property "Description" "25 MHz XO (Standard) LVPECL Oscillator 3.3V Enable/Disable 6-SMD, No Lead"
			(at 0 0 0)
			(layer "F.Fab")
			(hide yes)
			(effects
				(font
					(size 0.7 0.7)
					(thickness 0.15)
				)
				(justify right top)
			)
		)
		(property "Manufacturer" "Skyworks Solutions"
			(at 0 0 180)
			(unlocked yes)
			(layer "F.Fab")
			(hide yes)
			(effects
				(font
					(size 1 1)
					(thickness 0.15)
				)
			)
		)
		(property "MPN" "511ABA25M0000BAGR"
			(at 0 0 180)
			(unlocked yes)
			(layer "F.Fab")
			(hide yes)
			(effects
				(font
					(size 1 1)
					(thickness 0.15)
				)
			)
		)
		(property "Val" "25 MHz"
			(at 0 0 180)
			(unlocked yes)
			(layer "F.Fab")
			(hide yes)
			(effects
				(font
					(size 1 1)
					(thickness 0.15)
				)
			)
		)
		(property "Author" "Antmicro"
			(at 0 0 180)
			(unlocked yes)
			(layer "F.Fab")
			(hide yes)
			(effects
				(font
					(size 1 1)
					(thickness 0.15)
				)
			)
		)
		(property "License" "Apache-2.0"
			(at 0 0 180)
			(unlocked yes)
			(layer "F.Fab")
			(hide yes)
			(effects
				(font
					(size 1 1)
					(thickness 0.15)
				)
			)
		)
		(sheetname "/X710-AT2 10GbE/")
		(sheetfile "x710-at2-10gbe.kicad_sch")
		(attr smd)
		(fp_line
			(start 1.6 2.5)
			(end 1.6 1.95)
			(stroke
				(width 0.15)
				(type solid)
			)
			(layer "F.SilkS")
		)
		(fp_line
			(start 1.6 -2.5)
			(end 1.6 -1.95)
			(stroke
				(width 0.15)
				(type solid)
			)
			(layer "F.SilkS")
		)
		(fp_line
			(start 1.6 -2.5)
			(end -1.6 -2.5)
			(stroke
				(width 0.15)
				(type solid)
			)
			(layer "F.SilkS")
		)
		(fp_line
			(start -1.6 2.5)
			(end 1.6 2.5)
			(stroke
				(width 0.15)
				(type solid)
			)
			(layer "F.SilkS")
		)
		(fp_line
			(start -1.6 2.5)
			(end -1.6 1.95)
			(stroke
				(width 0.15)
				(type solid)
			)
			(layer "F.SilkS")
		)
		(fp_line
			(start -1.6 -2.5)
			(end -1.6 -1.95)
			(stroke
				(width 0.15)
				(type solid)
			)
			(layer "F.SilkS")
		)
		(fp_circle
			(center -1.95 -1.875)
			(end -1.9 -1.875)
			(stroke
				(width 0.15)
				(type solid)
			)
			(fill yes)
			(layer "F.SilkS")
		)
		(fp_rect
			(start -2.25 -2.75)
			(end 2.25 2.75)
			(stroke
				(width 0.05)
				(type solid)
			)
			(fill no)
			(layer "F.CrtYd")
		)
		(fp_line
			(start -0.9 -2.5)
			(end -1.6 -1.8)
			(stroke
				(width 0.15)
				(type solid)
			)
			(layer "F.Fab")
		)
		(fp_rect
			(start -1.6 -2.5)
			(end 1.6 2.5)
			(stroke
				(width 0.15)
				(type solid)
			)
			(fill no)
			(layer "F.Fab")
		)
		(pad "1" smd rect
			(at -1.3 -1.27 180)
			(size 1.7 0.8)
			(layers "F.Cu" "F.Mask" "F.Paste")
			(net 149 "/X710-AT2 10GbE/EN_OSC")
			(pinfunction "EN")
			(pintype "input")
		)
		(pad "2" smd rect
			(at -1.3 0 180)
			(size 1.7 0.8)
			(layers "F.Cu" "F.Mask" "F.Paste")
			(net 285 "unconnected-(Y1-NC-Pad2)")
			(pinfunction "NC")
			(pintype "no_connect")
		)
		(pad "3" smd rect
			(at -1.3 1.27 180)
			(size 1.7 0.8)
			(layers "F.Cu" "F.Mask" "F.Paste")
			(net 28 "GND")
			(pinfunction "GND")
			(pintype "power_in")
		)
		(pad "4" smd rect
			(at 1.3 1.27 180)
			(size 1.7 0.8)
			(layers "F.Cu" "F.Mask" "F.Paste")
			(net 143 "/X710-AT2 10GbE/25MHZ_OSC_R.+")
			(pinfunction "OUT+")
			(pintype "output")
		)
		(pad "5" smd rect
			(at 1.3 0 180)
			(size 1.7 0.8)
			(layers "F.Cu" "F.Mask" "F.Paste")
			(net 150 "/X710-AT2 10GbE/25MHZ_OSC_R.-")
			(pinfunction "OUT-")
			(pintype "output")
		)
		(pad "6" smd rect
			(at 1.3 -1.27 180)
			(size 1.7 0.8)
			(layers "F.Cu" "F.Mask" "F.Paste")
			(net 74 "/X710-AT2 10GbE/3V3_OSC")
			(pinfunction "VCC")
			(pintype "power_in")
		)
	)
)
